# T6G (Grand Teton) — schematic netlist excerpt (pin names and nets, part order shuffled) for the footprints in the layout excerpt that follows; sources: Cadence DE-HDL packaged netlist, KiCad conversion of 04192023_DAF0TMB3IC0_F0TG_MB_C_brd_V02_OCP.brd

C738  Q_CAP_DIFFBUS  DIFF BUS_0.22UF 6.3V 20% X6S  pkg C0201  page 66 : \1\ = P5E_CPU1_P1_TX_C_DN<1> ; \2\ = P5E_CPU1_P1_TX_DN<1>
R6085  Q_RES  10K 1% CHIP  pkg 0402LF  page 81 : A = P3V3_AUX ; B = PU_SPI_PLD_CS_N
PC6023  Q_CAP  100NF 50V 10% X7R  pkg C0402  page 270 : A = P12V_AUX ; B = GND

(kicad_pcb
	(version 20260206)
	(generator "pcbnew")
	(generator_version "10.0")
	(general
		(thickness 1.6)
		(legacy_teardrops no)
	)
	(paper "A4")
	(title_block
		(title "04192023_DAF0TMB3IC0_F0TG_MB_C_brd_V02_OCP.brd")
		(comment 1 "Grand Teton / footprints 49-51 of 8354")
	)
	(layers
		(0 "F.Cu" signal "TOP")
		(4 "In1.Cu" signal "GND")
		(6 "In2.Cu" signal "IN1")
		(8 "In3.Cu" signal "GND1")
		(10 "In4.Cu" signal "IN2")
		(12 "In5.Cu" signal "GND2")
		(14 "In6.Cu" signal "IN3")
		(16 "In7.Cu" signal "GND3")
		(18 "In8.Cu" signal "VCC")
		(20 "In9.Cu" signal "VCC1")
		(22 "In10.Cu" signal "GND4")
		(24 "In11.Cu" signal "IN4")
		(26 "In12.Cu" signal "GND5")
		(28 "In13.Cu" signal "IN5")
		(30 "In14.Cu" signal "GND6")
		(32 "In15.Cu" signal "IN6")
		(34 "In16.Cu" signal "GND7")
		(2 "B.Cu" signal "BOTTOM")
		(9 "F.Adhes" user "F.Adhesive")
		(11 "B.Adhes" user "B.Adhesive")
		(13 "F.Paste" user "Package Geometry/Pastemask Top")
		(15 "B.Paste" user "Package Geometry/Pastemask Bottom")
		(5 "F.SilkS" user "Ref Des/Silkscreen Top")
		(7 "B.SilkS" user "Ref Des/Silkscreen Bottom")
		(1 "F.Mask" user "Board Geometry/Soldermask Top")
		(3 "B.Mask" user "Board Geometry/Soldermask Bottom")
		(17 "Dwgs.User" user "User.Drawings")
		(19 "Cmts.User" user "User.Comments")
		(21 "Eco1.User" user "User.Eco1")
		(23 "Eco2.User" user "User.Eco2")
		(25 "Edge.Cuts" user "Board Geometry/Outline")
		(27 "Margin" user)
		(31 "F.CrtYd" user "Package Geometry/Place Bound Top")
		(29 "B.CrtYd" user "Package Geometry/Place Bound Bottom")
		(35 "F.Fab" user "Ref Des/Assembly Top")
		(33 "B.Fab" user "Ref Des/Assembly Bottom")
	)
	(footprint ""
		(layer "F.Cu")
		(at 196.088 -133.568948 -90)
		(property "Reference" "R6085"
			(at 0 0 270)
			(layer "F.SilkS")
			(hide yes)
			(effects
				(font
					(size 1.27 1.27)
				)
			)
		)
		(property "Value" ""
			(at 0 0 270)
			(layer "F.Fab")
			(effects
				(font
					(size 1.27 1.27)
				)
			)
		)
		(duplicate_pad_numbers_are_jumpers no)
		(fp_line
			(start -0.7874 0.4064)
			(end -0.7874 -0.4064)
			(stroke
				(width 0.1524)
				(type default)
			)
			(layer "F.SilkS")
		)
		(fp_line
			(start 0.7874 0.4064)
			(end -0.7874 0.4064)
			(stroke
				(width 0.1524)
				(type default)
			)
			(layer "F.SilkS")
		)
		(fp_line
			(start -0.7874 -0.4064)
			(end 0.7874 -0.4064)
			(stroke
				(width 0.1524)
				(type default)
			)
			(layer "F.SilkS")
		)
		(fp_line
			(start 0.7874 -0.4064)
			(end 0.7874 0.4064)
			(stroke
				(width 0.1524)
				(type default)
			)
			(layer "F.SilkS")
		)
		(fp_line
			(start -0.67945 0.3048)
			(end -0.67945 -0.305054)
			(stroke
				(width 0.1)
				(type default)
			)
			(layer "F.Fab")
		)
		(fp_line
			(start -0.12065 0.3048)
			(end -0.67945 0.3048)
			(stroke
				(width 0.1)
				(type default)
			)
			(layer "F.Fab")
		)
		(fp_line
			(start 0.120396 0.3048)
			(end 0.120396 0.2794)
			(stroke
				(width 0.1)
				(type default)
			)
			(layer "F.Fab")
		)
		(fp_line
			(start 0.67945 0.3048)
			(end 0.120396 0.3048)
			(stroke
				(width 0.1)
				(type default)
			)
			(layer "F.Fab")
		)
		(fp_line
			(start -0.12065 0.2794)
			(end -0.12065 0.3048)
			(stroke
				(width 0.1)
				(type default)
			)
			(layer "F.Fab")
		)
		(fp_line
			(start 0.120396 0.2794)
			(end -0.12065 0.2794)
			(stroke
				(width 0.1)
				(type default)
			)
			(layer "F.Fab")
		)
		(fp_line
			(start -0.12065 -0.2794)
			(end 0.12065 -0.2794)
			(stroke
				(width 0.1)
				(type default)
			)
			(layer "F.Fab")
		)
		(fp_line
			(start 0.12065 -0.2794)
			(end 0.12065 -0.3048)
			(stroke
				(width 0.1)
				(type default)
			)
			(layer "F.Fab")
		)
		(fp_line
			(start 0.12065 -0.3048)
			(end 0.67945 -0.3048)
			(stroke
				(width 0.1)
				(type default)
			)
			(layer "F.Fab")
		)
		(fp_line
			(start 0.67945 -0.3048)
			(end 0.67945 0.3048)
			(stroke
				(width 0.1)
				(type default)
			)
			(layer "F.Fab")
		)
		(fp_line
			(start -0.67945 -0.305054)
			(end -0.12065 -0.305054)
			(stroke
				(width 0.1)
				(type default)
			)
			(layer "F.Fab")
		)
		(fp_line
			(start -0.12065 -0.305054)
			(end -0.12065 -0.2794)
			(stroke
				(width 0.1)
				(type default)
			)
			(layer "F.Fab")
		)
		(pad "1" smd circle
			(at -0.40005 0 270)
			(size 0 0)
			(layers "F.Cu" "F.Mask" "F.Paste")
			(net "P3V3_AUX")
		)
		(pad "2" smd circle
			(at 0.40005 0 270)
			(size 0 0)
			(layers "F.Cu" "F.Mask" "F.Paste")
			(net "PU_SPI_PLD_CS_N")
		)
	)
	(footprint ""
		(layer "F.Cu")
		(at 115.024408 -71.962772 180)
		(property "Reference" "PC6023"
			(at 0 0 180)
			(layer "F.SilkS")
			(hide yes)
			(effects
				(font
					(size 1.27 1.27)
				)
			)
		)
		(property "Value" ""
			(at 0 0 180)
			(layer "F.Fab")
			(effects
				(font
					(size 1.27 1.27)
				)
			)
		)
		(duplicate_pad_numbers_are_jumpers no)
		(fp_line
			(start 0.7874 0.4064)
			(end -0.7874 0.4064)
			(stroke
				(width 0.1524)
				(type default)
			)
			(layer "F.SilkS")
		)
		(fp_line
			(start 0.7874 -0.4064)
			(end 0.7874 0.4064)
			(stroke
				(width 0.1524)
				(type default)
			)
			(layer "F.SilkS")
		)
		(fp_line
			(start -0.7874 0.4064)
			(end -0.7874 -0.4064)
			(stroke
				(width 0.1524)
				(type default)
			)
			(layer "F.SilkS")
		)
		(fp_line
			(start -0.7874 -0.4064)
			(end 0.7874 -0.4064)
			(stroke
				(width 0.1524)
				(type default)
			)
			(layer "F.SilkS")
		)
		(fp_line
			(start 0.67945 0.3048)
			(end 0.120396 0.3048)
			(stroke
				(width 0.1)
				(type default)
			)
			(layer "F.Fab")
		)
		(fp_line
			(start 0.67945 -0.3048)
			(end 0.67945 0.3048)
			(stroke
				(width 0.1)
				(type default)
			)
			(layer "F.Fab")
		)
		(fp_line
			(start 0.12065 -0.2794)
			(end 0.12065 -0.3048)
			(stroke
				(width 0.1)
				(type default)
			)
			(layer "F.Fab")
		)
		(fp_line
			(start 0.12065 -0.3048)
			(end 0.67945 -0.3048)
			(stroke
				(width 0.1)
				(type default)
			)
			(layer "F.Fab")
		)
		(fp_line
			(start 0.120396 0.3048)
			(end 0.120396 0.2794)
			(stroke
				(width 0.1)
				(type default)
			)
			(layer "F.Fab")
		)
		(fp_line
			(start 0.120396 0.2794)
			(end -0.12065 0.2794)
			(stroke
				(width 0.1)
				(type default)
			)
			(layer "F.Fab")
		)
		(fp_line
			(start -0.12065 0.3048)
			(end -0.67945 0.3048)
			(stroke
				(width 0.1)
				(type default)
			)
			(layer "F.Fab")
		)
		(fp_line
			(start -0.12065 0.2794)
			(end -0.12065 0.3048)
			(stroke
				(width 0.1)
				(type default)
			)
			(layer "F.Fab")
		)
		(fp_line
			(start -0.12065 -0.2794)
			(end 0.12065 -0.2794)
			(stroke
				(width 0.1)
				(type default)
			)
			(layer "F.Fab")
		)
		(fp_line
			(start -0.12065 -0.305054)
			(end -0.12065 -0.2794)
			(stroke
				(width 0.1)
				(type default)
			)
			(layer "F.Fab")
		)
		(fp_line
			(start -0.67945 0.3048)
			(end -0.67945 -0.305054)
			(stroke
				(width 0.1)
				(type default)
			)
			(layer "F.Fab")
		)
		(fp_line
			(start -0.67945 -0.305054)
			(end -0.12065 -0.305054)
			(stroke
				(width 0.1)
				(type default)
			)
			(layer "F.Fab")
		)
		(pad "1" smd circle
			(at -0.40005 0 180)
			(size 0 0)
			(layers "F.Cu" "F.Mask" "F.Paste")
			(net "P12V_AUX")
		)
		(pad "2" smd circle
			(at 0.40005 0 180)
			(size 0 0)
			(layers "F.Cu" "F.Mask" "F.Paste")
			(net "GND")
		)
	)
	(footprint ""
		(layer "F.Cu")
		(at 75.49515 -376.85726 180)
		(property "Reference" "C738"
			(at 0 0 180)
			(layer "F.SilkS")
			(hide yes)
			(effects
				(font
					(size 1.27 1.27)
				)
			)
		)
		(property "Value" ""
			(at 0 0 180)
			(layer "F.Fab")
			(effects
				(font
					(size 1.27 1.27)
				)
			)
		)
		(duplicate_pad_numbers_are_jumpers no)
		(fp_line
			(start 0.299974 0.150114)
			(end -0.299974 0.150114)
			(stroke
				(width 0.1)
				(type default)
			)
			(layer "F.Fab")
		)
		(fp_line
			(start 0.299974 -0.150114)
			(end 0.299974 0.150114)
			(stroke
				(width 0.1)
				(type default)
			)
			(layer "F.Fab")
		)
		(fp_line
			(start -0.299974 0.150114)
			(end -0.299974 -0.150114)
			(stroke
				(width 0.1)
				(type default)
			)
			(layer "F.Fab")
		)
		(fp_line
			(start -0.299974 -0.150114)
			(end 0.299974 -0.150114)
			(stroke
				(width 0.1)
				(type default)
			)
			(layer "F.Fab")
		)
		(pad "1" smd rect
			(at -0.2667 0 180)
			(size 0.3048 0.381)
			(layers "F.Cu" "F.Mask" "F.Paste")
			(net "P5E_CPU1_P1_TX_C_DN<1>")
		)
		(pad "2" smd rect
			(at 0.2667 0 180)
			(size 0.3048 0.381)
			(layers "F.Cu" "F.Mask" "F.Paste")
			(net "P5E_CPU1_P1_TX_DN<1>")
		)
	)
)
